# T6G (Grand Teton) — schematic netlist excerpt (pin names and nets, part order shuffled) for the footprints in the layout excerpt that follows; sources: Cadence DE-HDL packaged netlist, KiCad conversion of 04192023_DAF0TMB3IC0_F0TG_MB_C_brd_V02_OCP.brd

R2815  Q_RES  100K 1% EMPTY  pkg 0402LF  page 130 : A = P3V3_AUX ; B = BMC_MONITER_R
R1366  Q_RES  4.7K 5% CHIP  pkg 0201LF  page 185 : A = P1V8_CPU0_RT_1D ; B = SMB_RT_CPU0_P0_ROM_MUX_2D_R_SDA
C972  Q_CAP  0.1UF 10V 10% X7S  pkg C0201  page 301 : A = P0V9_CPU0_RT2_2A ; B = GND

(kicad_pcb
	(version 20260206)
	(generator "pcbnew")
	(generator_version "10.0")
	(general
		(thickness 1.6)
		(legacy_teardrops no)
	)
	(paper "A4")
	(title_block
		(title "04192023_DAF0TMB3IC0_F0TG_MB_C_brd_V02_OCP.brd")
		(comment 1 "Grand Teton / footprints 7284-7286 of 8354")
	)
	(layers
		(0 "F.Cu" signal "TOP")
		(4 "In1.Cu" signal "GND")
		(6 "In2.Cu" signal "IN1")
		(8 "In3.Cu" signal "GND1")
		(10 "In4.Cu" signal "IN2")
		(12 "In5.Cu" signal "GND2")
		(14 "In6.Cu" signal "IN3")
		(16 "In7.Cu" signal "GND3")
		(18 "In8.Cu" signal "VCC")
		(20 "In9.Cu" signal "VCC1")
		(22 "In10.Cu" signal "GND4")
		(24 "In11.Cu" signal "IN4")
		(26 "In12.Cu" signal "GND5")
		(28 "In13.Cu" signal "IN5")
		(30 "In14.Cu" signal "GND6")
		(32 "In15.Cu" signal "IN6")
		(34 "In16.Cu" signal "GND7")
		(2 "B.Cu" signal "BOTTOM")
		(9 "F.Adhes" user "F.Adhesive")
		(11 "B.Adhes" user "B.Adhesive")
		(13 "F.Paste" user "Package Geometry/Pastemask Top")
		(15 "B.Paste" user "Package Geometry/Pastemask Bottom")
		(5 "F.SilkS" user "Ref Des/Silkscreen Top")
		(7 "B.SilkS" user "Ref Des/Silkscreen Bottom")
		(1 "F.Mask" user "Board Geometry/Soldermask Top")
		(3 "B.Mask" user "Board Geometry/Soldermask Bottom")
		(17 "Dwgs.User" user "User.Drawings")
		(19 "Cmts.User" user "User.Comments")
		(21 "Eco1.User" user "User.Eco1")
		(23 "Eco2.User" user "User.Eco2")
		(25 "Edge.Cuts" user "Board Geometry/Outline")
		(27 "Margin" user)
		(31 "F.CrtYd" user "Package Geometry/Place Bound Top")
		(29 "B.CrtYd" user "Package Geometry/Place Bound Bottom")
		(35 "F.Fab" user "Ref Des/Assembly Top")
		(33 "B.Fab" user "Ref Des/Assembly Bottom")
	)
	(footprint ""
		(layer "B.Cu")
		(at 172.456094 -414.792668 180)
		(property "Reference" "R2815"
			(at 0 0 0)
			(layer "B.SilkS")
			(hide yes)
			(effects
				(font
					(size 1.27 1.27)
				)
				(justify mirror)
			)
		)
		(property "Value" ""
			(at 0 0 0)
			(layer "B.Fab")
			(effects
				(font
					(size 1.27 1.27)
				)
				(justify mirror)
			)
		)
		(duplicate_pad_numbers_are_jumpers no)
		(fp_line
			(start 0.7874 0.4064)
			(end 0.7874 -0.4064)
			(stroke
				(width 0.1524)
				(type default)
			)
			(layer "B.SilkS")
		)
		(fp_line
			(start 0.7874 -0.4064)
			(end -0.7874 -0.4064)
			(stroke
				(width 0.1524)
				(type default)
			)
			(layer "B.SilkS")
		)
		(fp_line
			(start -0.7874 0.4064)
			(end 0.7874 0.4064)
			(stroke
				(width 0.1524)
				(type default)
			)
			(layer "B.SilkS")
		)
		(fp_line
			(start -0.7874 -0.4064)
			(end -0.7874 0.4064)
			(stroke
				(width 0.1524)
				(type default)
			)
			(layer "B.SilkS")
		)
		(fp_line
			(start 0.67945 0.3048)
			(end 0.67945 -0.305054)
			(stroke
				(width 0.1)
				(type default)
			)
			(layer "B.Fab")
		)
		(fp_line
			(start 0.67945 -0.305054)
			(end 0.12065 -0.305054)
			(stroke
				(width 0.1)
				(type default)
			)
			(layer "B.Fab")
		)
		(fp_line
			(start 0.12065 0.3048)
			(end 0.67945 0.3048)
			(stroke
				(width 0.1)
				(type default)
			)
			(layer "B.Fab")
		)
		(fp_line
			(start 0.12065 0.2794)
			(end 0.12065 0.3048)
			(stroke
				(width 0.1)
				(type default)
			)
			(layer "B.Fab")
		)
		(fp_line
			(start 0.12065 -0.2794)
			(end -0.12065 -0.2794)
			(stroke
				(width 0.1)
				(type default)
			)
			(layer "B.Fab")
		)
		(fp_line
			(start 0.12065 -0.305054)
			(end 0.12065 -0.2794)
			(stroke
				(width 0.1)
				(type default)
			)
			(layer "B.Fab")
		)
		(fp_line
			(start -0.120396 0.3048)
			(end -0.120396 0.2794)
			(stroke
				(width 0.1)
				(type default)
			)
			(layer "B.Fab")
		)
		(fp_line
			(start -0.120396 0.2794)
			(end 0.12065 0.2794)
			(stroke
				(width 0.1)
				(type default)
			)
			(layer "B.Fab")
		)
		(fp_line
			(start -0.12065 -0.2794)
			(end -0.12065 -0.3048)
			(stroke
				(width 0.1)
				(type default)
			)
			(layer "B.Fab")
		)
		(fp_line
			(start -0.12065 -0.3048)
			(end -0.67945 -0.3048)
			(stroke
				(width 0.1)
				(type default)
			)
			(layer "B.Fab")
		)
		(fp_line
			(start -0.67945 0.3048)
			(end -0.120396 0.3048)
			(stroke
				(width 0.1)
				(type default)
			)
			(layer "B.Fab")
		)
		(fp_line
			(start -0.67945 -0.3048)
			(end -0.67945 0.3048)
			(stroke
				(width 0.1)
				(type default)
			)
			(layer "B.Fab")
		)
		(pad "1" smd circle
			(at 0.40005 0)
			(size 0 0)
			(layers "B.Cu" "B.Mask" "B.Paste")
			(net "P3V3_AUX")
		)
		(pad "2" smd circle
			(at -0.40005 0)
			(size 0 0)
			(layers "B.Cu" "B.Mask" "B.Paste")
			(net "BMC_MONITER_R")
		)
	)
	(footprint ""
		(layer "B.Cu")
		(at 405.546306 -396.393162 -90)
		(property "Reference" "C972"
			(at 0 0 90)
			(layer "B.SilkS")
			(hide yes)
			(effects
				(font
					(size 1.27 1.27)
				)
				(justify mirror)
			)
		)
		(property "Value" ""
			(at 0 0 90)
			(layer "B.Fab")
			(effects
				(font
					(size 1.27 1.27)
				)
				(justify mirror)
			)
		)
		(duplicate_pad_numbers_are_jumpers no)
		(fp_line
			(start -0.299974 0.150114)
			(end 0.299974 0.150114)
			(stroke
				(width 0.1)
				(type default)
			)
			(layer "B.Fab")
		)
		(fp_line
			(start 0.299974 0.150114)
			(end 0.299974 -0.150114)
			(stroke
				(width 0.1)
				(type default)
			)
			(layer "B.Fab")
		)
		(fp_line
			(start -0.299974 -0.150114)
			(end -0.299974 0.150114)
			(stroke
				(width 0.1)
				(type default)
			)
			(layer "B.Fab")
		)
		(fp_line
			(start 0.299974 -0.150114)
			(end -0.299974 -0.150114)
			(stroke
				(width 0.1)
				(type default)
			)
			(layer "B.Fab")
		)
		(pad "1" smd rect
			(at 0.2667 0 90)
			(size 0.3048 0.381)
			(layers "B.Cu" "B.Mask" "B.Paste")
			(net "P0V9_CPU0_RT2_2A")
		)
		(pad "2" smd rect
			(at -0.2667 0 90)
			(size 0.3048 0.381)
			(layers "B.Cu" "B.Mask" "B.Paste")
			(net "GND")
		)
	)
	(footprint ""
		(layer "B.Cu")
		(at 254.635 -341.884 180)
		(property "Reference" "R1366"
			(at 0 0 0)
			(layer "B.SilkS")
			(hide yes)
			(effects
				(font
					(size 1.27 1.27)
				)
				(justify mirror)
			)
		)
		(property "Value" ""
			(at 0 0 0)
			(layer "B.Fab")
			(effects
				(font
					(size 1.27 1.27)
				)
				(justify mirror)
			)
		)
		(duplicate_pad_numbers_are_jumpers no)
		(fp_line
			(start 0.32512 0.175006)
			(end 0.32512 -0.175006)
			(stroke
				(width 0.1)
				(type default)
			)
			(layer "B.Fab")
		)
		(fp_line
			(start 0.32512 -0.175006)
			(end -0.32512 -0.175006)
			(stroke
				(width 0.1)
				(type default)
			)
			(layer "B.Fab")
		)
		(fp_line
			(start -0.32512 0.175006)
			(end 0.32512 0.175006)
			(stroke
				(width 0.1)
				(type default)
			)
			(layer "B.Fab")
		)
		(fp_line
			(start -0.32512 -0.175006)
			(end -0.32512 0.175006)
			(stroke
				(width 0.1)
				(type default)
			)
			(layer "B.Fab")
		)
		(pad "1" smd rect
			(at 0.2667 0)
			(size 0.3048 0.381)
			(layers "B.Cu" "B.Mask" "B.Paste")
			(net "P1V8_CPU0_RT_1D")
		)
		(pad "2" smd rect
			(at -0.2667 0 180)
			(size 0.3048 0.381)
			(layers "B.Cu" "B.Mask" "B.Paste")
			(net "SMB_RT_CPU0_P0_ROM_MUX_2D_R_SDA")
		)
	)
)
